FILE_TYPE = CONNECTIVITY;
{Allegro Design Entry HDL 17.4-2019 S026 (4007227) 1/17/2022}
"PAGE_NUMBER" = 475;
0"NC";
1"GND\g";
2"GND\g";
3"GND\g";
4"GND\g";
5"GND\g";
6"GND\g";
7"GND\g";
8"GND\g";
9"GND\g";
10"GND\g";
11"GND\g";
12"GND\g";
13"P1V8_AUX\g";
14"GND\g";
15"P3V3_AUX\g";
16"GND\g";
17"GND\g";
18"GND\g";
19"P3V3_AUX\g";
20"P0V9_RETIMER_CPU0_IMON1";
21"P0V9_RETIMER_CPU0_SENSE_SH_N";
22"P0V9_RETIMER_CPU0_IMON2";
23"P0V9_RETIMER_CPU0_SENSE_R_P";
24"TP_P0V9_RETIMER_CPU0_VRHOT";
25"P0V9_RETIMER_CPU0_PMSDA";
26"P0V9_RETIMER_CPU0_PMSCL";
27"P0V9_RETIMER_CPU0_EN";
28"PWRGD_P0V9_RETIMER_CPU0";
29"P0V9_RETIMER_CPU0_SENSE_SH_P";
30"NC_P0V9_RETIMER_CPU0_IMON8";
31"P0V9_RETIMER_CPU0_TEMP0";
32"P0V9_RETIMER_CPU0_CFP";
33"NC_P0V9_RETIMER_CPU0_IMON6";
34"NC_P0V9_RETIMER_CPU0_PWM6";
35"NC_P0V9_RETIMER_CPU0_IMON7";
36"P0V9_RETIMER_CPU0_INALERT";
37"P0V9_RETIMER_CPU0_TEMP1_R";
38"NC_P0V9_RETIMER_CPU0_PWM7";
39"NC_P0V9_RETIMER_CPU0_PWM3";
40"NC_P0V9_RETIMER_CPU0_PWM4";
41"P0V9_RETIMER_CPU0_PMSDA_R";
42"P0V9_RETIMER_CPU0_EN0_R";
43"TP_P0V9_RETIMER_CPU0_PMALERT";
44"NC_P0V9_RETIMER_CPU0_PG1";
45"NC_P0V9_RETIMER_CPU0_IMON3";
46"P0V9_RETIMER_CPU0_VRHOT";
47"P0V9_RETIMER_CPU0_SVID_SDA";
48"P0V9_RETIMER_CPU0_PMSCL_R";
49"P0V9_RETIMER_CPU0_EN1_R";
50"PWRGD_P0V9_RETIMER_CPU0_R";
51"GND\g";
52"GND\g";
53"P12V_AUX\g";
54"GND\g";
55"P5V_AUX\g";
56"GND\g";
57"P0V9_CPU0_RT_2D\g";
58"P0V9_CPU0_RT_2D\g";
59"P3V3_AUX\g";
60"GND\g";
61"GND\g";
62"P3V3_AUX\g";
63"P0V9_RETIMER_CPU0_PWM2";
64"NC_P0V9_RETIMER_CPU0_IMON4";
65"NC_P0V9_RETIMER_CPU0_PWM5";
66"NC_P0V9_RETIMER_CPU0_IMON5";
67"P0V9_RETIMER_CPU0_ADDR";
68"P0V9_RETIMER_CPU0_VINSEN";
69"P0V9_RETIMER_CPU0_VMON";
70"NC_P0V9_RETIMER_CPU0_PWM8";
71"P0V9_RETIMER_CPU0_PWM1";
72"P3V3_AUX\g";
73"P0V9_RETIMER_CPU0_SVID_CLK";
74"TP_P0V9_RETIMER_CPU0_SVID_ALERT_N";
75"PV09_RETIMER_CPU0_VCCS";
76"GND\g";
77"P0V9_RETIMER_CPU0_VCC";
%"UNIVERSAL_GND"
"1","(-8900,2675)","0","pure_quanta_power","I10";
;
CDS_LIB"pure_quanta_power"
HDL_POWER"GND";
"A"1;
%"Q_RES"
"1","(-8900,5875)","0","pure_quanta","I105";
;
LOCATION"PR6531"
SEC"1"
TOLERANCE"5%"
VALUE"0"
PACK_TYPE"0402LF"
WATTAGE"1/16W"
MATERIAL"CHIP"
SEC_TYPE"0402LF"
CDS_LIB"pure_quanta"
PART_NUMBER"CS00002JB13";
"B"
$PN"2"23;
"A"
$PN"1"29;
%"Q_CAP"
"2","(-8450,8025)","0","pure_quanta","I118";
;
LOCATION"C101"
SEC"1"
TOLERANCE"5%"
MATERIAL"EMPTY"
VALUE"1000PF"
VOLTAGE"50V"
PACK_TYPE"0402"
SEC_TYPE"0402"
CDS_LIB"pure_quanta"
PART_NUMBER"TMP_QCH21006JB10";
"A"
$PN"1"50;
"B"
$PN"2"16;
%"Q_RES"
"1","(-9950,7875)","0","pure_quanta","I119";
;
LOCATION"R650"
SEC"1"
VALUE"0"
TOLERANCE"5%"
PACK_TYPE"0402LF"
MATERIAL"CHIP"
WATTAGE"1/16W"
SEC_TYPE"0402LF"
CDS_LIB"pure_quanta"
PART_NUMBER"CS00002JB13";
"B"
$PN"2"50;
"A"
$PN"1"28;
%"Q_RES"
"1","(-9300,7725)","0","pure_quanta","I120";
;
LOCATION"R651"
SEC"1"
TOLERANCE"5%"
VALUE"0"
PACK_TYPE"0402LF"
MATERIAL"CHIP"
WATTAGE"1/16W"
SEC_TYPE"0402LF"
CDS_LIB"pure_quanta"
PART_NUMBER"CS00002JB13";
"B"
$PN"2"42;
"A"
$PN"1"27;
%"Q_CAP"
"1","(-8450,5700)","0","pure_quanta","I121";
;
LOCATION"PC6540"
SEC"1"
VALUE"3300PF"
MATERIAL"X7R"
PACK_TYPE"0402"
VOLTAGE"50V"
TOLERANCE"10%"
SEC_TYPE"0402"
CDS_LIB"pure_quanta"
PART_NUMBER"TMP_QCH2336K1B12";
"B"
$PN"2"21;
"A"
$PN"1"23;
%"Q_CAP"
"1","(-7925,2100)","0","pure_quanta","I123";
;
LOCATION"PC6602"
SEC"1"
MATERIAL"X7R"
TOLERANCE"10%"
VALUE"0.1UF"
PACK_TYPE"0402"
VOLTAGE"25V"
SEC_TYPE"0402"
CDS_LIB"pure_quanta"
PART_NUMBER"CH4104K1B00";
"B"
$PN"2"61;
"A"
$PN"1"68;
%"Q_RES"
"2","(-8050,2100)","2","pure_quanta","I125";
;
LOCATION"PR6607"
$SEC"1"
CDS_SEC"1"
MATERIAL"EMPTY"
PACK_TYPE"0402LF"
WATTAGE"1/16W"
TOLERANCE"1%"
VALUE"1K"
CDS_LIB"pure_quanta"
PART_NUMBER"CS21002FB06";
"A"
$PN"1"68;
"B"
$PN"2"61;
%"Q_RES"
"2","(-9100,4075)","2","pure_quanta","I127";
;
LOCATION"R655"
SEC"1"
VALUE"1K"
TOLERANCE"1%"
WATTAGE"1/16W"
PACK_TYPE"0402LF"
MATERIAL"CHIP"
SEC_TYPE"0402LF"
CDS_LIB"pure_quanta"
PART_NUMBER"CS21002FB06";
"A"
$PN"1"59;
"B"
$PN"2"36;
%"Q_RES"
"2","(-8725,4075)","2","pure_quanta","I128";
;
LOCATION"R652"
SEC"1"
PACK_TYPE"0402LF"
TOLERANCE"1%"
VALUE"1K"
MATERIAL"CHIP"
WATTAGE"1/16W"
SEC_TYPE"0402LF"
CDS_LIB"pure_quanta"
PART_NUMBER"CS21002FB06";
"A"
$PN"1"59;
"B"
$PN"2"32;
%"Q_RES"
"1","(-4950,7875)","0","pure_quanta","I131";
;
LOCATION"PR6608"
SEC"1"
PACK_TYPE"0402LF"
TOLERANCE"1%"
WATTAGE"1/16W"
VALUE"1"
MATERIAL"CHIP"
SEC_TYPE"0402LF"
CDS_LIB"pure_quanta"
PART_NUMBER"CS-1002FB04";
"B"
$PN"2"62;
"A"
$PN"1"77;
%"Q_CAP"
"1","(-5275,7675)","0","pure_quanta","I132";
;
LOCATION"PC6604"
SEC"1"
PACK_TYPE"C0402"
VALUE"1UF"
VOLTAGE"16V"
TOLERANCE"10%"
MATERIAL"X6S"
SEC_TYPE"C0402"
CDS_LIB"pure_quanta"
PART_NUMBER"CH5103KEB01";
"B"
$PN"2"76;
"A"
$PN"1"77;
%"Q_RES"
"2","(-3525,3625)","0","pure_quanta","I135";
;
LOCATION"PR6615"
SEC"1"
VALUE"1K"
PACK_TYPE"0402LF"
TOLERANCE"1%"
MATERIAL"CHIP"
WATTAGE"1/16W"
CDS_LIB"pure_quanta"
SEC_TYPE"0402LF"
PART_NUMBER"CS21002FB06";
"A"
$PN"1"19;
"B"
$PN"2"24;
%"Q_RES"
"1","(-4775,3375)","0","pure_quanta","I136";
;
LOCATION"PR6616"
SEC"1"
WATTAGE"1/16W"
TOLERANCE"5%"
MATERIAL"CHIP"
VALUE"0"
SEC_TYPE"0402LF"
CDS_LIB"pure_quanta"
PACK_TYPE"0402LF"
PART_NUMBER"CS00002JB13";
"B"
$PN"2"24;
"A"
$PN"1"46;
%"Q_RES"
"2","(-4600,2475)","0","pure_quanta","I138";
;
LOCATION"PR6814"
SEC"1"
WATTAGE"1/16W"
MATERIAL"EMPTY"
PACK_TYPE"0402LF"
VALUE"10K"
TOLERANCE"1%"
SEC_TYPE"0402LF"
CDS_LIB"pure_quanta"
PART_NUMBER"CS31002FB08";
"A"
$PN"1"31;
"B"
$PN"2"18;
%"Q_CAP"
"1","(-5675,7675)","0","pure_quanta","I144";
;
LOCATION"PC6603"
SEC"1"
PACK_TYPE"C0402"
VALUE"100NF"
VOLTAGE"50V"
MATERIAL"X7R"
TOLERANCE"10%"
CDS_LIB"pure_quanta"
SEC_TYPE"C0402"
PART_NUMBER"CH4106K1B01";
"B"
$PN"2"76;
"A"
$PN"1"77;
%"Q_CAP"
"1","(-5675,7200)","0","pure_quanta","I145";
;
LOCATION"PC6606"
SEC"1"
VALUE"10UF"
MATERIAL"X6S"
VOLTAGE"6.3V"
TOLERANCE"20%"
PACK_TYPE"C0402"
SEC_TYPE"C0402"
CDS_LIB"pure_quanta"
PART_NUMBER"CH6101MEB03";
"B"
$PN"2"51;
"A"
$PN"1"75;
%"Q_CAP"
"1","(-5275,7200)","0","pure_quanta","I146";
;
LOCATION"PC6605"
SEC"1"
PACK_TYPE"C0402"
MATERIAL"X6S"
TOLERANCE"10%"
VOLTAGE"16V"
VALUE"1UF"
SEC_TYPE"C0402"
CDS_LIB"pure_quanta"
PART_NUMBER"CH5103KEB01";
"B"
$PN"2"51;
"A"
$PN"1"75;
%"Q_CAP"
"1","(-5300,2475)","0","pure_quanta","I148";
;
LOCATION"PC6607"
SEC"1"
MATERIAL"X7R"
PACK_TYPE"0402"
VALUE"470PF"
TOLERANCE"10%"
VOLTAGE"50V"
SEC_TYPE"0402"
CDS_LIB"pure_quanta"
PART_NUMBER"TMP_QCH14706KB18";
"B"
$PN"2"17;
"A"
$PN"1"31;
%"Q_RES"
"2","(-8800,2100)","2","pure_quanta","I150";
;
LOCATION"PR6605"
SEC"1"
PACK_TYPE"0402LF"
VALUE"0"
TOLERANCE"5%"
WATTAGE"1/16W"
MATERIAL"CHIP"
SEC_TYPE"0402LF"
CDS_LIB"pure_quanta"
PART_NUMBER"CS00002JB13";
"A"
$PN"1"69;
"B"
$PN"2"56;
%"Q_CAP"
"1","(-8675,2100)","0","pure_quanta","I151";
;
LOCATION"PC6601"
SEC"1"
MATERIAL"EMPTY"
PACK_TYPE"0402"
TOLERANCE"10%"
VALUE"0.1UF"
VOLTAGE"25V"
SEC_TYPE"0402"
CDS_LIB"pure_quanta"
PART_NUMBER"CH4104K1B00";
"B"
$PN"2"56;
"A"
$PN"1"69;
%"UNIVERSAL_GND"
"1","(-9150,6800)","5","pure_quanta_power","I154";
;
CDS_LIB"pure_quanta_power"
HDL_POWER"GND";
"A"52;
%"Q_RES"
"1","(-9100,2525)","0","pure_quanta","I158";
;
LOCATION"PR6807"
SEC"1"
MATERIAL"EMPTY"
TOLERANCE"5%"
VALUE"0"
WATTAGE"1/16W"
PACK_TYPE"0402LF"
SEC_TYPE"0402LF"
CDS_LIB"pure_quanta"
PART_NUMBER"CS00002JB13";
"B"
$PN"2"69;
"A"
$PN"1"53;
%"VCC15"
"1","(-9500,2650)","0","pure_quanta_power","I159";
;
HDL_POWER"P12V_AUX"
CDS_LIB"pure_quanta_power";
"A"53;
%"Q_RES"
"1","(-9100,2425)","0","pure_quanta","I160";
;
LOCATION"PR6606"
SEC"1"
VALUE"0"
TOLERANCE"5%"
MATERIAL"CHIP"
WATTAGE"1/16W"
PACK_TYPE"0402LF"
SEC_TYPE"0402LF"
CDS_LIB"pure_quanta"
PART_NUMBER"CS00002JB13";
"B"
$PN"2"68;
"A"
$PN"1"53;
%"Q_RES"
"1","(-10175,3400)","0","pure_quanta","I161";
;
LOCATION"R6801"
SEC"1"
MATERIAL"CHIP"
WATTAGE"1/16W"
PACK_TYPE"0402LF"
TOLERANCE"5%"
VALUE"0"
SEC_TYPE"0402LF"
CDS_LIB"pure_quanta"
PART_NUMBER"CS00002JB13";
"B"
$PN"2"49;
"A"
$PN"1"2;
%"UNIVERSAL_GND"
"1","(-10675,3400)","5","pure_quanta_power","I162";
;
CDS_LIB"pure_quanta_power"
HDL_POWER"GND";
"A"2;
%"VCC15"
"1","(-9875,7550)","0","pure_quanta_power","I164";
;
HDL_POWER"P3V3_AUX"
CDS_LIB"pure_quanta_power";
"A"72;
%"Q_RES"
"2","(-9000,6950)","0","pure_quanta","I165";
;
LOCATION"PR6810"
SEC"1"
PACK_TYPE"0402LF"
MATERIAL"CHIP"
VALUE"0"
TOLERANCE"5%"
WATTAGE"1/16W"
CDS_LIB"pure_quanta"
SEC_TYPE"0402LF"
PART_NUMBER"CS00002JB13";
"A"
$PN"1"73;
"B"
$PN"2"52;
%"Q_RES"
"1","(-9375,7425)","0","pure_quanta","I166";
;
LOCATION"PR6805"
SEC"1"
MATERIAL"EMPTY"
VALUE"1K"
TOLERANCE"1%"
WATTAGE"1/16W"
PACK_TYPE"0402LF"
CDS_LIB"pure_quanta"
SEC_TYPE"0402LF"
PART_NUMBER"CS21002FB06";
"B"
$PN"2"73;
"A"
$PN"1"72;
%"Q_RES"
"1","(-9375,7275)","0","pure_quanta","I167";
;
LOCATION"PR6803"
SEC"1"
TOLERANCE"1%"
VALUE"1K"
MATERIAL"EMPTY"
PACK_TYPE"0402LF"
SEC_TYPE"0402LF"
WATTAGE"1/16W"
CDS_LIB"pure_quanta"
PART_NUMBER"CS21002FB06";
"B"
$PN"2"47;
"A"
$PN"1"72;
%"Q_RES"
"2","(-8650,6950)","0","pure_quanta","I168";
;
LOCATION"PR6819"
SEC"1"
PACK_TYPE"0402LF"
TOLERANCE"5%"
MATERIAL"CHIP"
VALUE"0"
WATTAGE"1/16W"
CDS_LIB"pure_quanta"
SEC_TYPE"0402LF"
PART_NUMBER"CS00002JB13";
"A"
$PN"1"47;
"B"
$PN"2"52;
%"Q_RES"
"1","(-9375,7125)","0","pure_quanta","I169";
;
LOCATION"PR6817"
SEC"1"
MATERIAL"EMPTY"
VALUE"1K"
TOLERANCE"1%"
CDS_LIB"pure_quanta"
SEC_TYPE"0402LF"
WATTAGE"1/16W"
PACK_TYPE"0402LF"
PART_NUMBER"CS21002FB06";
"B"
$PN"2"74;
"A"
$PN"1"72;
%"UNIVERSAL_GND"
"1","(-7800,4350)","0","pure_quanta_power","I172";
;
CDS_LIB"pure_quanta_power"
HDL_POWER"GND";
"A"54;
%"VCC15"
"1","(-9800,2450)","0","pure_quanta_power","I176";
;
HDL_POWER"P5V_AUX"
CDS_LIB"pure_quanta_power";
"A"55;
%"Q_RES"
"1","(-9500,2300)","0","pure_quanta","I178";
;
LOCATION"PR6604"
SEC"1"
VALUE"5.36K"
WATTAGE"1/16W"
TOLERANCE"1%"
MATERIAL"EMPTY"
PACK_TYPE"0402LF"
SEC_TYPE"0402LF"
CDS_LIB"pure_quanta"
PART_NUMBER"CS25362FB02";
"B"
$PN"2"69;
"A"
$PN"1"55;
%"Q_RES"
"1","(-8550,2775)","0","pure_quanta","I183";
;
LOCATION"PR6603"
SEC"1"
TOLERANCE"5%"
VALUE"0"
SEC_TYPE"0402LF"
PACK_TYPE"0402LF"
CDS_LIB"pure_quanta"
MATERIAL"CHIP"
WATTAGE"1/16W"
PART_NUMBER"CS00002JB13";
"B"
$PN"2"67;
"A"
$PN"1"1;
%"Q_RES"
"1","(-4800,5875)","0","pure_quanta","I188";
;
LOCATION"PR6609"
$SEC"1"
CDS_SEC"1"
TOLERANCE"5%"
VALUE"0"
MATERIAL"CHIP"
WATTAGE"1/16W"
CDS_LIB"pure_quanta"
PACK_TYPE"0402LF"
PART_NUMBER"CS00002JB13";
"B"
$PN"2"3;
"A"
$PN"1"45;
%"UNIVERSAL_GND"
"1","(-4475,5725)","0","pure_quanta_power","I189";
;
CDS_LIB"pure_quanta_power"
HDL_POWER"GND";
"A"3;
%"Q_RES"
"1","(-4800,5425)","0","pure_quanta","I190";
;
LOCATION"PR6610"
$SEC"1"
CDS_SEC"1"
MATERIAL"CHIP"
WATTAGE"1/16W"
TOLERANCE"5%"
VALUE"0"
CDS_LIB"pure_quanta"
PACK_TYPE"0402LF"
PART_NUMBER"CS00002JB13";
"B"
$PN"2"4;
"A"
$PN"1"64;
%"Q_RES"
"1","(-4775,4975)","0","pure_quanta","I191";
;
LOCATION"PR6611"
$SEC"1"
CDS_SEC"1"
MATERIAL"CHIP"
WATTAGE"1/16W"
TOLERANCE"5%"
VALUE"0"
PACK_TYPE"0402LF"
CDS_LIB"pure_quanta"
PART_NUMBER"CS00002JB13";
"B"
$PN"2"5;
"A"
$PN"1"66;
%"Q_RES"
"1","(-4775,4525)","0","pure_quanta","I192";
;
LOCATION"PR6612"
$SEC"1"
CDS_SEC"1"
WATTAGE"1/16W"
MATERIAL"CHIP"
TOLERANCE"5%"
VALUE"0"
PACK_TYPE"0402LF"
CDS_LIB"pure_quanta"
PART_NUMBER"CS00002JB13";
"B"
$PN"2"6;
"A"
$PN"1"33;
%"Q_RES"
"1","(-4775,4075)","0","pure_quanta","I193";
;
LOCATION"PR6613"
$SEC"1"
CDS_SEC"1"
MATERIAL"CHIP"
TOLERANCE"5%"
VALUE"0"
WATTAGE"1/16W"
CDS_LIB"pure_quanta"
PACK_TYPE"0402LF"
PART_NUMBER"CS00002JB13";
"B"
$PN"2"7;
"A"
$PN"1"35;
%"UNIVERSAL_GND"
"1","(-4450,5225)","0","pure_quanta_power","I194";
;
CDS_LIB"pure_quanta_power"
HDL_POWER"GND";
"A"4;
%"UNIVERSAL_GND"
"1","(-4450,4750)","0","pure_quanta_power","I195";
;
CDS_LIB"pure_quanta_power"
HDL_POWER"GND";
"A"5;
%"UNIVERSAL_GND"
"1","(-4425,4275)","0","pure_quanta_power","I196";
;
CDS_LIB"pure_quanta_power"
HDL_POWER"GND";
"A"6;
%"UNIVERSAL_GND"
"1","(-4450,3850)","0","pure_quanta_power","I197";
;
CDS_LIB"pure_quanta_power"
HDL_POWER"GND";
"A"7;
%"Q_RES"
"1","(-4825,3625)","0","pure_quanta","I198";
;
LOCATION"PR6614"
$SEC"1"
CDS_SEC"1"
VALUE"0"
WATTAGE"1/16W"
TOLERANCE"5%"
MATERIAL"CHIP"
PACK_TYPE"0402LF"
CDS_LIB"pure_quanta"
PART_NUMBER"CS00002JB13";
"B"
$PN"2"8;
"A"
$PN"1"30;
%"UNIVERSAL_GND"
"1","(-4375,3450)","0","pure_quanta_power","I199";
;
CDS_LIB"pure_quanta_power"
HDL_POWER"GND";
"A"8;
%"UNIVERSAL_GND"
"1","(-8675,1800)","0","pure_quanta_power","I2";
;
CDS_LIB"pure_quanta_power"
HDL_POWER"GND";
"A"56;
%"VCC15"
"1","(-10850,6175)","0","pure_quanta_power","I200";
;
HDL_POWER"P0V9_CPU0_RT_2D"
CDS_LIB"pure_quanta_power";
"A"57;
%"UNIVERSAL_GND"
"1","(-10850,5250)","0","pure_quanta_power","I202";
;
CDS_LIB"pure_quanta_power"
HDL_POWER"GND";
"A"9;
%"UNIVERSAL_GND"
"1","(-7800,4575)","0","pure_quanta_power","I203";
;
CDS_LIB"pure_quanta_power"
HDL_POWER"GND";
"A"10;
%"Q_RES"
"1","(-4825,2975)","0","pure_quanta","I204";
;
LOCATION"PR6618"
$SEC"1"
CDS_SEC"1"
WATTAGE"1/16W"
MATERIAL"CHIP"
VALUE"0"
TOLERANCE"5%"
PACK_TYPE"0402LF"
CDS_LIB"pure_quanta"
PART_NUMBER"CS00002JB13";
"B"
$PN"2"11;
"A"
$PN"1"37;
%"UNIVERSAL_GND"
"1","(-4550,2850)","0","pure_quanta_power","I205";
;
CDS_LIB"pure_quanta_power"
HDL_POWER"GND";
"A"11;
%"Q_RES"
"1","(-9300,6425)","0","pure_quanta","I207";
;
LOCATION"R649"
$SEC"1"
CDS_SEC"1"
MATERIAL"EMPTY"
VALUE"4.7K"
TOLERANCE"1%"
CDS_LIB"pure_quanta"
PACK_TYPE"0402LF"
WATTAGE"1/16W"
PART_NUMBER"CS24702FB06";
"B"
$PN"2"43;
"A"
$PN"1"72;
%"Q_RES"
"2","(-10475,7450)","2","pure_quanta","I208";
;
LOCATION"R6786"
$SEC"1"
CDS_SEC"1"
PACK_TYPE"0402LF"
TOLERANCE"1%"
VALUE"1K"
WATTAGE"1/16W"
MATERIAL"CHIP"
CDS_LIB"pure_quanta"
PART_NUMBER"CS21002FB06";
"A"
$PN"1"42;
"B"
$PN"2"12;
%"UNIVERSAL_GND"
"1","(-10475,7150)","0","pure_quanta_power","I209";
;
CDS_LIB"pure_quanta_power"
HDL_POWER"GND";
"A"12;
%"Q_RES"
"2","(-8300,6950)","0","pure_quanta","I210";
;
LOCATION"PR883"
$SEC"1"
CDS_SEC"1"
MATERIAL"EMPTY"
VALUE"0"
WATTAGE"1/16W"
TOLERANCE"5%"
PACK_TYPE"0402LF"
CDS_LIB"pure_quanta"
PART_NUMBER"CS00002JB13";
"A"
$PN"1"74;
"B"
$PN"2"52;
%"VCC15"
"1","(-10325,8150)","0","pure_quanta_power","I211";
;
HDL_POWER"P1V8_AUX"
CDS_LIB"pure_quanta_power";
"A"13;
%"Q_RES"
"1","(-9150,8025)","0","pure_quanta","I212";
;
LOCATION"R643"
$SEC"1"
CDS_SEC"1"
TOLERANCE"1%"
MATERIAL"EMPTY"
WATTAGE"1/16W"
PACK_TYPE"0402LF"
VALUE"1K"
CDS_LIB"pure_quanta"
PART_NUMBER"CS21002FB06";
"B"
$PN"2"50;
"A"
$PN"1"15;
%"Q_RES"
"1","(-9950,8050)","0","pure_quanta","I213";
;
LOCATION"R6860"
$SEC"1"
CDS_SEC"1"
PACK_TYPE"0402LF"
MATERIAL"CHIP"
VALUE"1K"
TOLERANCE"1%"
WATTAGE"1/16W"
CDS_LIB"pure_quanta"
PART_NUMBER"CS21002FB06";
"B"
$PN"2"50;
"A"
$PN"1"13;
%"Q_SHORT"
"1","(-10550,5875)","0","pure_quanta","I214";
;
LOCATION"PJ09_P0_P"
SEC"1"
MATERIAL"EMPTY"
PACK_TYPE"SM"
CDS_LIB"pure_quanta"
NEEDS_NO_SIZE"TRUE"
SEC_TYPE"SM"
PART_NUMBER"SHORT16";
"1"
$PN"1"57;
"2"
$PN"2"29;
%"Q_SHORT"
"1","(-10550,5500)","0","pure_quanta","I215";
;
LOCATION"PJ09_P0_N"
SEC"1"
MATERIAL"EMPTY"
PACK_TYPE"SM"
SEC_TYPE"SM"
CDS_LIB"pure_quanta"
NEEDS_NO_SIZE"TRUE"
PART_NUMBER"SHORT16";
"1"
$PN"1"9;
"2"
$PN"2"21;
%"Q_RES"
"1","(-9975,5350)","0","pure_quanta","I32";
;
LOCATION"PR6532"
$SEC"1"
CDS_SEC"1"
TOLERANCE"1%"
VALUE"49.9"
PACK_TYPE"0402LF"
MATERIAL"CHIP"
WATTAGE"1/16W"
CDS_LIB"pure_quanta"
PART_NUMBER"CS04992FB07";
"B"
$PN"2"14;
"A"
$PN"1"21;
%"Q_RES"
"1","(-9925,6025)","0","pure_quanta","I34";
;
LOCATION"PR6530"
$SEC"1"
CDS_SEC"1"
VALUE"49.9"
TOLERANCE"1%"
MATERIAL"CHIP"
WATTAGE"1/16W"
PACK_TYPE"0402LF"
CDS_LIB"pure_quanta"
PART_NUMBER"CS04992FB07";
"B"
$PN"2"58;
"A"
$PN"1"29;
%"UNIVERSAL_GND"
"1","(-9450,5250)","0","pure_quanta_power","I35";
;
CDS_LIB"pure_quanta_power"
HDL_POWER"GND";
"A"14;
%"VCC15"
"1","(-9425,6175)","0","pure_quanta_power","I36";
;
HDL_POWER"P0V9_CPU0_RT_2D"
CDS_LIB"pure_quanta_power";
"A"58;
%"VCC15"
"1","(-9100,4300)","0","pure_quanta_power","I37";
;
HDL_POWER"P3V3_AUX"
CDS_LIB"pure_quanta_power";
"A"59;
%"UNIVERSAL_GND"
"1","(-7700,2200)","0","pure_quanta_power","I41";
;
CDS_LIB"pure_quanta_power"
HDL_POWER"GND";
"A"60;
%"ISL69260IRAZT"
"1","(-6575,5125)","0","pure_quanta","I42";
;
LOCATION"PU6502"
SEC"1"
MATERIAL"IC"
PART_TYPE"SMLF"
VALUE"ISL69260IRAZ-T"
NEEDS_NO_SIZE"TRUE"
CDS_LIB"pure_quanta"
CDS_LMAN_SYM_OUTLINE"-550,2850,500,-2850"
SEC_TYPE""
PART_NUMBER"AL069260000";
"CS0"
$PN"30"30;
"PWM0"
$PN"1"70;
"TEMP0"
$PN"35"31;
"ADDR_CFG"
$PN"34"67;
"TH_GND"
$PN"TH"60;
"CFP"
$PN"33"32;
"CS2"
$PN"28"33;
"PWM2"
$PN"3"34;
"CS3"
$PN"27"66;
"PWM3"
$PN"4"65;
"PWM7"
$PN"8"71;
"CS1"
$PN"29"35;
"RGND1"
$PN"31"54;
"VSEN1"
$PN"32"10;
"NPINALERT#||NPSYSCRIT# \B"
$PN"15"36;
"TEMP1||ISYS"
$PN"36"37;
"VINSEN||VSYS"
$PN"38"68;
"VMON||IINSEN||VSYS||ISYS"
$PN"37"69;
"VCCS"
$PN"40"75;
"PWM6"
$PN"7"63;
"PG0"
$PN"12"50;
"PWM1"
$PN"2"38;
"VSEN0"
$PN"21"23;
"PWM5"
$PN"6"39;
"PWM4"
$PN"5"40;
"PMSDA"
$PN"9"41;
"RGND0"
$PN"22"21;
"EN0"
$PN"13"42;
"NPMALERT# \B"
$PN"11"43;
"SVCLK"
$PN"17"73;
"PG1"
$PN"16"44;
"CS4"
$PN"26"64;
"CS5"
$PN"25"45;
"NVRHOT# \B"
$PN"14"46;
"NSVALERT# \B"
$PN"19"74;
"CS6"
$PN"24"22;
"SVDATA"
$PN"18"47;
"PMSCL"
$PN"10"48;
"EN1"
$PN"20"49;
"VCC"
$PN"39"77;
"CS7"
$PN"23"20;
%"UNIVERSAL_GND"
"1","(-7925,1800)","0","pure_quanta_power","I5";
;
CDS_LIB"pure_quanta_power"
HDL_POWER"GND";
"A"61;
%"VCC15"
"1","(-9500,8150)","0","pure_quanta_power","I51";
;
HDL_POWER"P3V3_AUX"
CDS_LIB"pure_quanta_power";
"A"15;
%"UNIVERSAL_GND"
"1","(-7750,8025)","1","pure_quanta_power","I55";
;
CDS_LIB"pure_quanta_power"
HDL_POWER"GND";
"A"16;
%"UNIVERSAL_GND"
"1","(-5300,2250)","0","pure_quanta_power","I56";
;
CDS_LIB"pure_quanta_power"
HDL_POWER"GND";
"A"17;
%"UNIVERSAL_GND"
"1","(-4600,2225)","0","pure_quanta_power","I58";
;
CDS_LIB"pure_quanta_power"
HDL_POWER"GND";
"A"18;
%"VCC15"
"1","(-3525,3825)","0","pure_quanta_power","I74";
;
HDL_POWER"P3V3_AUX"
CDS_LIB"pure_quanta_power";
"A"19;
%"UNIVERSAL_GND"
"1","(-4825,7000)","3","pure_quanta_power","I89";
;
CDS_LIB"pure_quanta_power"
HDL_POWER"GND";
"A"51;
%"UNIVERSAL_GND"
"1","(-4825,7475)","3","pure_quanta_power","I91";
;
CDS_LIB"pure_quanta_power"
HDL_POWER"GND";
"A"76;
%"VCC15"
"1","(-4475,8000)","0","pure_quanta_power","I93";
;
HDL_POWER"P3V3_AUX"
CDS_LIB"pure_quanta_power";
"A"62;
%"Q_RES"
"1","(-9300,6725)","0","pure_quanta","I94";
;
LOCATION"R646"
SEC"1"
MATERIAL"CHIP"
PACK_TYPE"0402LF"
TOLERANCE"5%"
VALUE"0"
WATTAGE"1/16W"
SEC_TYPE"0402LF"
CDS_LIB"pure_quanta"
PART_NUMBER"CS00002JB13";
"B"
$PN"2"48;
"A"
$PN"1"26;
%"Q_RES"
"1","(-9300,6575)","0","pure_quanta","I95";
;
LOCATION"R647"
SEC"1"
TOLERANCE"5%"
VALUE"0"
CDS_LIB"pure_quanta"
SEC_TYPE"0402LF"
MATERIAL"CHIP"
WATTAGE"1/16W"
PACK_TYPE"0402LF"
PART_NUMBER"CS00002JB13";
"B"
$PN"2"41;
"A"
$PN"1"25;
END.
